(kicad_pcb
	(version 20241229)
	(generator "pcbnew")
	(generator_version "9.0")
	(general
		(thickness 1.61)
		(legacy_teardrops no)
	)
	(paper "A3")
	(title_block
		(title "SO-DIMM DDR5 Tester")
		(date "2025-11-26")
		(rev "1.3.0")
		(comment 9 "footprints 395-400 of 627")
	)
	(layers
		(0 "F.Cu" signal)
		(4 "In1.Cu" power)
		(6 "In2.Cu" mixed)
		(8 "In3.Cu" power)
		(10 "In4.Cu" mixed)
		(12 "In5.Cu" power)
		(14 "In6.Cu" mixed)
		(16 "In7.Cu" power)
		(18 "In8.Cu" power)
		(20 "In9.Cu" mixed)
		(22 "In10.Cu" power)
		(2 "B.Cu" signal)
		(9 "F.Adhes" user "F.Adhesive")
		(11 "B.Adhes" user "B.Adhesive")
		(13 "F.Paste" user)
		(15 "B.Paste" user)
		(5 "F.SilkS" user "F.Silkscreen")
		(7 "B.SilkS" user "B.Silkscreen")
		(1 "F.Mask" user)
		(3 "B.Mask" user)
		(17 "Dwgs.User" user "User.Drawings")
		(19 "Cmts.User" user "User.Comments")
		(21 "Eco1.User" user "User.Eco1")
		(23 "Eco2.User" user "User.Eco2")
		(25 "Edge.Cuts" user)
		(27 "Margin" user)
		(31 "F.CrtYd" user "F.Courtyard")
		(29 "B.CrtYd" user "B.Courtyard")
		(35 "F.Fab" user)
		(33 "B.Fab" user)
	)
	(footprint "antmicro-footprints:C_0603_1608Metric"
		(layer "B.Cu")
		(at 117.150501 204.176 180)
		(descr "Capacitor SMD 0603")
		(tags "capacitor 0603")
		(property "Reference" "C224"
			(at -1.42757 1.000252 0)
			(layer "B.SilkS")
			(hide yes)
			(effects
				(font
					(size 0.7 0.7)
					(thickness 0.15)
				)
				(justify left bottom mirror)
			)
		)
		(property "Value" "C_10u_25V_0603"
			(at -1.42757 -1.770288 0)
			(layer "B.Fab")
			(effects
				(font
					(size 0.7 0.7)
					(thickness 0.15)
				)
				(justify left bottom mirror)
			)
		)
		(property "Datasheet" "https://product.tdk.com/en/search/capacitor/ceramic/mlcc/info?part_no=C1608X5R1E106M080AC"
			(at 0 0 180)
			(layer "F.Fab")
			(hide yes)
			(effects
				(font
					(size 1.27 1.27)
					(thickness 0.15)
				)
			)
		)
		(property "Author" "Antmicro"
			(at 234.301002 408.352 0)
			(layer "B.Fab")
			(hide yes)
			(effects
				(font
					(size 1 1)
					(thickness 0.15)
				)
				(justify mirror)
			)
		)
		(property "Dielectric" ""
			(at 234.301002 408.352 0)
			(layer "B.Fab")
			(hide yes)
			(effects
				(font
					(size 1 1)
					(thickness 0.15)
				)
				(justify mirror)
			)
		)
		(property "License" "Apache-2.0"
			(at 234.301002 408.352 0)
			(layer "B.Fab")
			(hide yes)
			(effects
				(font
					(size 1 1)
					(thickness 0.15)
				)
				(justify mirror)
			)
		)
		(property "MPN" "C1608X5R1E106M080AC"
			(at 234.301002 408.352 0)
			(layer "B.Fab")
			(hide yes)
			(effects
				(font
					(size 1 1)
					(thickness 0.15)
				)
				(justify mirror)
			)
		)
		(property "Manufacturer" "TDK"
			(at 234.301002 408.352 0)
			(layer "B.Fab")
			(hide yes)
			(effects
				(font
					(size 1 1)
					(thickness 0.15)
				)
				(justify mirror)
			)
		)
		(property "Val" "10u/25V"
			(at 234.301002 408.352 0)
			(layer "B.Fab")
			(hide yes)
			(effects
				(font
					(size 1 1)
					(thickness 0.15)
				)
				(justify mirror)
			)
		)
		(property "Voltage" ""
			(at 234.301002 408.352 0)
			(layer "B.Fab")
			(hide yes)
			(effects
				(font
					(size 1 1)
					(thickness 0.15)
				)
				(justify mirror)
			)
		)
		(sheetname "/PCIe connector/")
		(sheetfile "pcie-connector.kicad_sch")
		(attr smd)
		(fp_line
			(start -0.3 0.3)
			(end 0.3 0.3)
			(stroke
				(width 0.15)
				(type solid)
			)
			(layer "B.SilkS")
		)
		(fp_line
			(start -0.3 -0.3)
			(end 0.3 -0.3)
			(stroke
				(width 0.15)
				(type solid)
			)
			(layer "B.SilkS")
		)
		(fp_rect
			(start -1.24 0.7)
			(end 1.24 -0.7)
			(stroke
				(width 0.05)
				(type solid)
			)
			(fill no)
			(layer "B.CrtYd")
		)
		(fp_rect
			(start -0.8 0.4)
			(end 0.8 -0.4)
			(stroke
				(width 0.15)
				(type solid)
			)
			(fill no)
			(layer "B.Fab")
		)
		(pad "1" smd roundrect
			(at -0.7 0 180)
			(size 0.6 0.8)
			(layers "B.Cu" "B.Mask" "B.Paste")
			(roundrect_rratio 0.2)
			(net 1 "GND")
			(pintype "passive")
		)
		(pad "2" smd roundrect
			(at 0.7 0 180)
			(size 0.6 0.8)
			(layers "B.Cu" "B.Mask" "B.Paste")
			(roundrect_rratio 0.2)
			(net 11 "+12V")
			(pintype "passive")
		)
	)
	(footprint "antmicro-footprints:C_0402_1005Metric"
		(layer "B.Cu")
		(at 149.377001 181.8005 90)
		(descr "Capacitor SMD 0402 (1005 Metric), square (rectangular) end terminal, IPC_7351 nominal, (Body size source: IPC-SM-782 page 76, https://www.pcb-3d.com/wordpress/wp-content/uploads/ipc-sm-782a_amendment_1_and_2.pdf)")
		(tags "capacitor 0402")
		(property "Reference" "C106"
			(at 0 1.17 270)
			(layer "B.SilkS")
			(hide yes)
			(effects
				(font
					(size 0.7 0.7)
					(thickness 0.15)
				)
				(justify left bottom mirror)
			)
		)
		(property "Value" "C_100n_0402"
			(at 0 -1.169 270)
			(layer "B.Fab")
			(effects
				(font
					(size 0.7 0.7)
					(thickness 0.15)
				)
				(justify left bottom mirror)
			)
		)
		(property "Datasheet" "https://www.murata.com/products/productdetail?partno=GRM155R61H104KE14%23"
			(at 0 0 90)
			(layer "F.Fab")
			(hide yes)
			(effects
				(font
					(size 1.27 1.27)
					(thickness 0.15)
				)
			)
		)
		(property "Author" "Antmicro"
			(at 331.177501 32.423499 0)
			(layer "B.Fab")
			(hide yes)
			(effects
				(font
					(size 1 1)
					(thickness 0.15)
				)
				(justify mirror)
			)
		)
		(property "Dielectric" "X5R"
			(at 331.177501 32.423499 0)
			(layer "B.Fab")
			(hide yes)
			(effects
				(font
					(size 1 1)
					(thickness 0.15)
				)
				(justify mirror)
			)
		)
		(property "License" "Apache-2.0"
			(at 331.177501 32.423499 0)
			(layer "B.Fab")
			(hide yes)
			(effects
				(font
					(size 1 1)
					(thickness 0.15)
				)
				(justify mirror)
			)
		)
		(property "MPN" "GRM155R61H104KE14D"
			(at 331.177501 32.423499 0)
			(layer "B.Fab")
			(hide yes)
			(effects
				(font
					(size 1 1)
					(thickness 0.15)
				)
				(justify mirror)
			)
		)
		(property "Manufacturer" "Murata"
			(at 331.177501 32.423499 0)
			(layer "B.Fab")
			(hide yes)
			(effects
				(font
					(size 1 1)
					(thickness 0.15)
				)
				(justify mirror)
			)
		)
		(property "Val" "100n"
			(at 331.177501 32.423499 0)
			(layer "B.Fab")
			(hide yes)
			(effects
				(font
					(size 1 1)
					(thickness 0.15)
				)
				(justify mirror)
			)
		)
		(property "Voltage" "50V"
			(at 331.177501 32.423499 0)
			(layer "B.Fab")
			(hide yes)
			(effects
				(font
					(size 1 1)
					(thickness 0.15)
				)
				(justify mirror)
			)
		)
		(sheetname "/FPGA power/")
		(sheetfile "fpga-power.kicad_sch")
		(attr smd)
		(fp_rect
			(start -0.9656 0.4572)
			(end 0.9652 -0.4828)
			(stroke
				(width 0.05)
				(type solid)
			)
			(fill no)
			(layer "B.CrtYd")
		)
		(fp_line
			(start 0.498 -0.248)
			(end -0.5 -0.248)
			(stroke
				(width 0.15)
				(type solid)
			)
			(layer "B.Fab")
		)
		(fp_line
			(start -0.5 -0.248)
			(end -0.5 0.25)
			(stroke
				(width 0.15)
				(type solid)
			)
			(layer "B.Fab")
		)
		(fp_line
			(start 0.498 0.25)
			(end 0.498 -0.248)
			(stroke
				(width 0.15)
				(type solid)
			)
			(layer "B.Fab")
		)
		(fp_line
			(start -0.5 0.25)
			(end 0.498 0.25)
			(stroke
				(width 0.15)
				(type solid)
			)
			(layer "B.Fab")
		)
		(pad "1" smd roundrect
			(at -0.5 0)
			(size 0.6 0.6)
			(layers "B.Cu" "B.Mask" "B.Paste")
			(roundrect_rratio 0.25)
			(net 1 "GND")
			(pintype "passive")
		)
		(pad "2" smd roundrect
			(at 0.498 0 90)
			(size 0.6 0.6)
			(layers "B.Cu" "B.Mask" "B.Paste")
			(roundrect_rratio 0.25)
			(net 226 "+1V2_MGTAVTT")
			(pintype "passive")
		)
	)
	(footprint "antmicro-footprints:R_0402_1005Metric"
		(layer "B.Cu")
		(at 196.65 138.75 90)
		(descr "Resistor SMD 0402")
		(tags "resistor SMD 0402")
		(property "Reference" "R149"
			(at -1.122484 0.772697 270)
			(layer "B.SilkS")
			(hide yes)
			(effects
				(font
					(size 0.7 0.7)
					(thickness 0.15)
				)
				(justify left bottom mirror)
			)
		)
		(property "Value" "R_47k_0402"
			(at -1.011843 -1.772047 270)
			(layer "B.Fab")
			(effects
				(font
					(size 0.7 0.7)
					(thickness 0.15)
				)
				(justify left bottom mirror)
			)
		)
		(property "Datasheet" "https://www.bourns.com/docs/product-datasheets/cr.pdf"
			(at 0 0 90)
			(layer "F.Fab")
			(hide yes)
			(effects
				(font
					(size 1.27 1.27)
					(thickness 0.15)
				)
			)
		)
		(property "Author" "Antmicro"
			(at 335.4 -57.9 0)
			(layer "B.Fab")
			(hide yes)
			(effects
				(font
					(size 1 1)
					(thickness 0.15)
				)
				(justify mirror)
			)
		)
		(property "License" "Apache-2.0"
			(at 335.4 -57.9 0)
			(layer "B.Fab")
			(hide yes)
			(effects
				(font
					(size 1 1)
					(thickness 0.15)
				)
				(justify mirror)
			)
		)
		(property "MPN" "CR0402-FX-4702GLF"
			(at 335.4 -57.9 0)
			(layer "B.Fab")
			(hide yes)
			(effects
				(font
					(size 1 1)
					(thickness 0.15)
				)
				(justify mirror)
			)
		)
		(property "Manufacturer" "Bourns"
			(at 335.4 -57.9 0)
			(layer "B.Fab")
			(hide yes)
			(effects
				(font
					(size 1 1)
					(thickness 0.15)
				)
				(justify mirror)
			)
		)
		(property "Tolerance" "1%"
			(at 335.4 -57.9 0)
			(layer "B.Fab")
			(hide yes)
			(effects
				(font
					(size 1 1)
					(thickness 0.15)
				)
				(justify mirror)
			)
		)
		(property "Val" "47k"
			(at 335.4 -57.9 0)
			(layer "B.Fab")
			(hide yes)
			(effects
				(font
					(size 1 1)
					(thickness 0.15)
				)
				(justify mirror)
			)
		)
		(sheetname "/Supply/")
		(sheetfile "supply.kicad_sch")
		(attr smd)
		(fp_rect
			(start -0.93 0.47)
			(end 0.93 -0.47)
			(stroke
				(width 0.05)
				(type solid)
			)
			(fill no)
			(layer "B.CrtYd")
		)
		(fp_rect
			(start -0.5 0.25)
			(end 0.5 -0.25)
			(stroke
				(width 0.15)
				(type solid)
			)
			(fill no)
			(layer "B.Fab")
		)
		(pad "1" smd roundrect
			(at -0.485 0 90)
			(size 0.59 0.64)
			(layers "B.Cu" "B.Mask" "B.Paste")
			(roundrect_rratio 0.25)
			(net 185 "/Supply/~{PB_CTRL_CLR}")
			(pintype "passive")
		)
		(pad "2" smd roundrect
			(at 0.485 0 90)
			(size 0.59 0.64)
			(layers "B.Cu" "B.Mask" "B.Paste")
			(roundrect_rratio 0.25)
			(net 186 "/Supply/PB_CTRL_OUT")
			(pintype "passive")
		)
	)
	(footprint "antmicro-footprints:C_0402_1005Metric"
		(layer "B.Cu")
		(at 137.875001 177.3025)
		(descr "Capacitor SMD 0402 (1005 Metric), square (rectangular) end terminal, IPC_7351 nominal, (Body size source: IPC-SM-782 page 76, https://www.pcb-3d.com/wordpress/wp-content/uploads/ipc-sm-782a_amendment_1_and_2.pdf)")
		(tags "capacitor 0402")
		(property "Reference" "C70"
			(at 0 1.17 180)
			(layer "B.SilkS")
			(hide yes)
			(effects
				(font
					(size 0.7 0.7)
					(thickness 0.15)
				)
				(justify left bottom mirror)
			)
		)
		(property "Value" "C_100n_0402"
			(at 0 -1.169 180)
			(layer "B.Fab")
			(effects
				(font
					(size 0.7 0.7)
					(thickness 0.15)
				)
				(justify left bottom mirror)
			)
		)
		(property "Datasheet" "https://www.murata.com/products/productdetail?partno=GRM155R61H104KE14%23"
			(at 0 0 0)
			(layer "F.Fab")
			(hide yes)
			(effects
				(font
					(size 1.27 1.27)
					(thickness 0.15)
				)
			)
		)
		(property "Author" "Antmicro"
			(at 0 0 0)
			(layer "B.Fab")
			(hide yes)
			(effects
				(font
					(size 1 1)
					(thickness 0.15)
				)
				(justify mirror)
			)
		)
		(property "Dielectric" "X5R"
			(at 0 0 0)
			(layer "B.Fab")
			(hide yes)
			(effects
				(font
					(size 1 1)
					(thickness 0.15)
				)
				(justify mirror)
			)
		)
		(property "License" "Apache-2.0"
			(at 0 0 0)
			(layer "B.Fab")
			(hide yes)
			(effects
				(font
					(size 1 1)
					(thickness 0.15)
				)
				(justify mirror)
			)
		)
		(property "MPN" "GRM155R61H104KE14D"
			(at 0 0 0)
			(layer "B.Fab")
			(hide yes)
			(effects
				(font
					(size 1 1)
					(thickness 0.15)
				)
				(justify mirror)
			)
		)
		(property "Manufacturer" "Murata"
			(at 0 0 0)
			(layer "B.Fab")
			(hide yes)
			(effects
				(font
					(size 1 1)
					(thickness 0.15)
				)
				(justify mirror)
			)
		)
		(property "Val" "100n"
			(at 0 0 0)
			(layer "B.Fab")
			(hide yes)
			(effects
				(font
					(size 1 1)
					(thickness 0.15)
				)
				(justify mirror)
			)
		)
		(property "Voltage" "50V"
			(at 0 0 0)
			(layer "B.Fab")
			(hide yes)
			(effects
				(font
					(size 1 1)
					(thickness 0.15)
				)
				(justify mirror)
			)
		)
		(sheetname "/FPGA power/")
		(sheetfile "fpga-power.kicad_sch")
		(attr smd)
		(fp_rect
			(start -0.9656 0.4572)
			(end 0.9652 -0.4828)
			(stroke
				(width 0.05)
				(type solid)
			)
			(fill no)
			(layer "B.CrtYd")
		)
		(fp_line
			(start -0.5 -0.248)
			(end -0.5 0.25)
			(stroke
				(width 0.15)
				(type solid)
			)
			(layer "B.Fab")
		)
		(fp_line
			(start -0.5 0.25)
			(end 0.498 0.25)
			(stroke
				(width 0.15)
				(type solid)
			)
			(layer "B.Fab")
		)
		(fp_line
			(start 0.498 -0.248)
			(end -0.5 -0.248)
			(stroke
				(width 0.15)
				(type solid)
			)
			(layer "B.Fab")
		)
		(fp_line
			(start 0.498 0.25)
			(end 0.498 -0.248)
			(stroke
				(width 0.15)
				(type solid)
			)
			(layer "B.Fab")
		)
		(pad "1" smd roundrect
			(at -0.5 0 270)
			(size 0.6 0.6)
			(layers "B.Cu" "B.Mask" "B.Paste")
			(roundrect_rratio 0.25)
			(net 1 "GND")
			(pintype "passive")
		)
		(pad "2" smd roundrect
			(at 0.498 0)
			(size 0.6 0.6)
			(layers "B.Cu" "B.Mask" "B.Paste")
			(roundrect_rratio 0.25)
			(net 227 "+1V0")
			(pintype "passive")
		)
	)
	(footprint "antmicro-footprints:C_0402_1005Metric"
		(layer "B.Cu")
		(at 136.877001 173.3025)
		(descr "Capacitor SMD 0402 (1005 Metric), square (rectangular) end terminal, IPC_7351 nominal, (Body size source: IPC-SM-782 page 76, https://www.pcb-3d.com/wordpress/wp-content/uploads/ipc-sm-782a_amendment_1_and_2.pdf)")
		(tags "capacitor 0402")
		(property "Reference" "C62"
			(at 0 1.17 180)
			(layer "B.SilkS")
			(hide yes)
			(effects
				(font
					(size 0.7 0.7)
					(thickness 0.15)
				)
				(justify left bottom mirror)
			)
		)
		(property "Value" "C_4u7_0402"
			(at 0 -1.169 180)
			(layer "B.Fab")
			(effects
				(font
					(size 0.7 0.7)
					(thickness 0.15)
				)
				(justify left bottom mirror)
			)
		)
		(property "Datasheet" "https://www.murata.com/products/productdetail?partno=GRM155R61A475MEAA%23"
			(at 0 0 0)
			(layer "F.Fab")
			(hide yes)
			(effects
				(font
					(size 1.27 1.27)
					(thickness 0.15)
				)
			)
		)
		(property "Author" "Antmicro"
			(at 0 0 0)
			(layer "B.Fab")
			(hide yes)
			(effects
				(font
					(size 1 1)
					(thickness 0.15)
				)
				(justify mirror)
			)
		)
		(property "Dielectric" ""
			(at 0 0 0)
			(layer "B.Fab")
			(hide yes)
			(effects
				(font
					(size 1 1)
					(thickness 0.15)
				)
				(justify mirror)
			)
		)
		(property "License" "Apache-2.0"
			(at 0 0 0)
			(layer "B.Fab")
			(hide yes)
			(effects
				(font
					(size 1 1)
					(thickness 0.15)
				)
				(justify mirror)
			)
		)
		(property "MPN" "GRM155R61A475MEAAD"
			(at 0 0 0)
			(layer "B.Fab")
			(hide yes)
			(effects
				(font
					(size 1 1)
					(thickness 0.15)
				)
				(justify mirror)
			)
		)
		(property "Manufacturer" "Murata"
			(at 0 0 0)
			(layer "B.Fab")
			(hide yes)
			(effects
				(font
					(size 1 1)
					(thickness 0.15)
				)
				(justify mirror)
			)
		)
		(property "Val" "4u7"
			(at 0 0 0)
			(layer "B.Fab")
			(hide yes)
			(effects
				(font
					(size 1 1)
					(thickness 0.15)
				)
				(justify mirror)
			)
		)
		(property "Voltage" ""
			(at 0 0 0)
			(layer "B.Fab")
			(hide yes)
			(effects
				(font
					(size 1 1)
					(thickness 0.15)
				)
				(justify mirror)
			)
		)
		(sheetname "/FPGA power/")
		(sheetfile "fpga-power.kicad_sch")
		(attr smd)
		(fp_rect
			(start -0.9656 0.4572)
			(end 0.9652 -0.4828)
			(stroke
				(width 0.05)
				(type solid)
			)
			(fill no)
			(layer "B.CrtYd")
		)
		(fp_line
			(start -0.5 -0.248)
			(end -0.5 0.25)
			(stroke
				(width 0.15)
				(type solid)
			)
			(layer "B.Fab")
		)
		(fp_line
			(start -0.5 0.25)
			(end 0.498 0.25)
			(stroke
				(width 0.15)
				(type solid)
			)
			(layer "B.Fab")
		)
		(fp_line
			(start 0.498 -0.248)
			(end -0.5 -0.248)
			(stroke
				(width 0.15)
				(type solid)
			)
			(layer "B.Fab")
		)
		(fp_line
			(start 0.498 0.25)
			(end 0.498 -0.248)
			(stroke
				(width 0.15)
				(type solid)
			)
			(layer "B.Fab")
		)
		(pad "1" smd roundrect
			(at -0.5 0 270)
			(size 0.6 0.6)
			(layers "B.Cu" "B.Mask" "B.Paste")
			(roundrect_rratio 0.25)
			(net 227 "+1V0")
			(pintype "passive")
		)
		(pad "2" smd roundrect
			(at 0.498 0)
			(size 0.6 0.6)
			(layers "B.Cu" "B.Mask" "B.Paste")
			(roundrect_rratio 0.25)
			(net 1 "GND")
			(pintype "passive")
		)
	)
	(footprint "antmicro-footprints:C_0402_1005Metric"
		(layer "B.Cu")
		(at 195.85 128.15 180)
		(descr "Capacitor SMD 0402")
		(tags "capacitor SMD 0402")
		(property "Reference" "C169"
			(at 0 0.699 0)
			(layer "B.SilkS")
			(hide yes)
			(effects
				(font
					(size 0.7 0.7)
					(thickness 0.15)
				)
				(justify left bottom mirror)
			)
		)
		(property "Value" "C_100n_0402"
			(at -1.022927 -2.155213 0)
			(layer "B.Fab")
			(effects
				(font
					(size 0.7 0.7)
					(thickness 0.15)
				)
				(justify left bottom mirror)
			)
		)
		(property "Datasheet" "https://www.murata.com/products/productdetail?partno=GRM155R61H104KE14%23"
			(at 0 0 180)
			(layer "F.Fab")
			(hide yes)
			(effects
				(font
					(size 1.27 1.27)
					(thickness 0.15)
				)
			)
		)
		(property "Author" "Antmicro"
			(at 391.7 256.3 0)
			(layer "B.Fab")
			(hide yes)
			(effects
				(font
					(size 1 1)
					(thickness 0.15)
				)
				(justify mirror)
			)
		)
		(property "Dielectric" "X5R"
			(at 391.7 256.3 0)
			(layer "B.Fab")
			(hide yes)
			(effects
				(font
					(size 1 1)
					(thickness 0.15)
				)
				(justify mirror)
			)
		)
		(property "License" "Apache-2.0"
			(at 391.7 256.3 0)
			(layer "B.Fab")
			(hide yes)
			(effects
				(font
					(size 1 1)
					(thickness 0.15)
				)
				(justify mirror)
			)
		)
		(property "MPN" "GRM155R61H104KE14D"
			(at 391.7 256.3 0)
			(layer "B.Fab")
			(hide yes)
			(effects
				(font
					(size 1 1)
					(thickness 0.15)
				)
				(justify mirror)
			)
		)
		(property "Manufacturer" "Murata"
			(at 391.7 256.3 0)
			(layer "B.Fab")
			(hide yes)
			(effects
				(font
					(size 1 1)
					(thickness 0.15)
				)
				(justify mirror)
			)
		)
		(property "Val" "100n"
			(at 391.7 256.3 0)
			(layer "B.Fab")
			(hide yes)
			(effects
				(font
					(size 1 1)
					(thickness 0.15)
				)
				(justify mirror)
			)
		)
		(property "Voltage" "50V"
			(at 391.7 256.3 0)
			(layer "B.Fab")
			(hide yes)
			(effects
				(font
					(size 1 1)
					(thickness 0.15)
				)
				(justify mirror)
			)
		)
		(sheetname "/Supply/")
		(sheetfile "supply.kicad_sch")
		(attr smd)
		(fp_rect
			(start -0.9659 0.481258)
			(end 0.9649 -0.458742)
			(stroke
				(width 0.05)
				(type solid)
			)
			(fill no)
			(layer "B.CrtYd")
		)
		(fp_line
			(start 0.499 0.25)
			(end 0.499 -0.248)
			(stroke
				(width 0.15)
				(type solid)
			)
			(layer "B.Fab")
		)
		(fp_line
			(start 0.499 -0.248)
			(end -0.499 -0.248)
			(stroke
				(width 0.15)
				(type solid)
			)
			(layer "B.Fab")
		)
		(fp_line
			(start -0.499 0.25)
			(end 0.499 0.25)
			(stroke
				(width 0.15)
				(type solid)
			)
			(layer "B.Fab")
		)
		(fp_line
			(start -0.499 -0.248)
			(end -0.499 0.25)
			(stroke
				(width 0.15)
				(type solid)
			)
			(layer "B.Fab")
		)
		(pad "1" smd roundrect
			(at -0.484 0 180)
			(size 0.59 0.64)
			(layers "B.Cu" "B.Mask" "B.Paste")
			(roundrect_rratio 0.25)
			(net 1 "GND")
			(pintype "passive")
		)
		(pad "2" smd roundrect
			(at 0.484 0 180)
			(size 0.59 0.64)
			(layers "B.Cu" "B.Mask" "B.Paste")
			(roundrect_rratio 0.25)
			(net 597 "/Supply/12V_aux")
			(pintype "passive")
		)
	)
)
